(kicad_pcb
	(version 20260206)
	(generator "pcbnew")
	(generator_version "10.0")
	(general
		(thickness 1.6)
		(legacy_teardrops no)
	)
	(paper "A4")
	(title_block
		(title "01162023_DA0F0TEBIF0_F0T_Expander_BD_F_brd_V02_OCP.brd")
		(comment 1 "Grand Teton / footprints 3533-3540 of 9728")
	)
	(layers
		(0 "F.Cu" signal "TOP")
		(4 "In1.Cu" signal "GND")
		(6 "In2.Cu" signal "VCC")
		(8 "In3.Cu" signal "VCC1")
		(10 "In4.Cu" signal "GND1")
		(12 "In5.Cu" signal "IN1")
		(14 "In6.Cu" signal "GND2")
		(16 "In7.Cu" signal "IN2")
		(18 "In8.Cu" signal "GND3")
		(20 "In9.Cu" signal "IN3")
		(22 "In10.Cu" signal "GND4")
		(24 "In11.Cu" signal "IN4")
		(26 "In12.Cu" signal "GND5")
		(28 "In13.Cu" signal "IN5")
		(30 "In14.Cu" signal "GND6")
		(32 "In15.Cu" signal "IN6")
		(34 "In16.Cu" signal "GND7")
		(2 "B.Cu" signal "BOTTOM")
		(9 "F.Adhes" user "F.Adhesive")
		(11 "B.Adhes" user "B.Adhesive")
		(13 "F.Paste" user "Package Geometry/Pastemask Top")
		(15 "B.Paste" user "Package Geometry/Pastemask Bottom")
		(5 "F.SilkS" user "Ref Des/Silkscreen Top")
		(7 "B.SilkS" user "Ref Des/Silkscreen Bottom")
		(1 "F.Mask" user "Board Geometry/Soldermask Top")
		(3 "B.Mask" user "Board Geometry/Soldermask Bottom")
		(17 "Dwgs.User" user "User.Drawings")
		(19 "Cmts.User" user "User.Comments")
		(21 "Eco1.User" user "User.Eco1")
		(23 "Eco2.User" user "User.Eco2")
		(25 "Edge.Cuts" user "Board Geometry/Outline")
		(27 "Margin" user)
		(31 "F.CrtYd" user "Package Geometry/Place Bound Top")
		(29 "B.CrtYd" user "Package Geometry/Place Bound Bottom")
		(35 "F.Fab" user "Ref Des/Assembly Top")
		(33 "B.Fab" user "Ref Des/Assembly Bottom")
	)
	(footprint ""
		(layer "F.Cu")
		(at 86.94039 -143.182848 90)
		(property "Reference" "C3999"
			(at 0 0 90)
			(layer "F.SilkS")
			(hide yes)
			(effects
				(font
					(size 1.27 1.27)
				)
			)
		)
		(property "Value" ""
			(at 0 0 90)
			(layer "F.Fab")
			(effects
				(font
					(size 1.27 1.27)
				)
			)
		)
		(duplicate_pad_numbers_are_jumpers no)
		(fp_line
			(start 0.7874 -0.4064)
			(end 0.7874 0.4064)
			(stroke
				(width 0.1524)
				(type default)
			)
			(layer "F.SilkS")
		)
		(fp_line
			(start -0.7874 -0.4064)
			(end 0.7874 -0.4064)
			(stroke
				(width 0.1524)
				(type default)
			)
			(layer "F.SilkS")
		)
		(fp_line
			(start 0.7874 0.4064)
			(end -0.7874 0.4064)
			(stroke
				(width 0.1524)
				(type default)
			)
			(layer "F.SilkS")
		)
		(fp_line
			(start -0.7874 0.4064)
			(end -0.7874 -0.4064)
			(stroke
				(width 0.1524)
				(type default)
			)
			(layer "F.SilkS")
		)
		(fp_line
			(start -0.12065 -0.305054)
			(end -0.12065 -0.2794)
			(stroke
				(width 0.1)
				(type default)
			)
			(layer "F.Fab")
		)
		(fp_line
			(start -0.67945 -0.305054)
			(end -0.12065 -0.305054)
			(stroke
				(width 0.1)
				(type default)
			)
			(layer "F.Fab")
		)
		(fp_line
			(start 0.67945 -0.3048)
			(end 0.67945 0.3048)
			(stroke
				(width 0.1)
				(type default)
			)
			(layer "F.Fab")
		)
		(fp_line
			(start 0.12065 -0.3048)
			(end 0.67945 -0.3048)
			(stroke
				(width 0.1)
				(type default)
			)
			(layer "F.Fab")
		)
		(fp_line
			(start 0.12065 -0.2794)
			(end 0.12065 -0.3048)
			(stroke
				(width 0.1)
				(type default)
			)
			(layer "F.Fab")
		)
		(fp_line
			(start -0.12065 -0.2794)
			(end 0.12065 -0.2794)
			(stroke
				(width 0.1)
				(type default)
			)
			(layer "F.Fab")
		)
		(fp_line
			(start 0.120396 0.2794)
			(end -0.12065 0.2794)
			(stroke
				(width 0.1)
				(type default)
			)
			(layer "F.Fab")
		)
		(fp_line
			(start -0.12065 0.2794)
			(end -0.12065 0.3048)
			(stroke
				(width 0.1)
				(type default)
			)
			(layer "F.Fab")
		)
		(fp_line
			(start 0.67945 0.3048)
			(end 0.120396 0.3048)
			(stroke
				(width 0.1)
				(type default)
			)
			(layer "F.Fab")
		)
		(fp_line
			(start 0.120396 0.3048)
			(end 0.120396 0.2794)
			(stroke
				(width 0.1)
				(type default)
			)
			(layer "F.Fab")
		)
		(fp_line
			(start -0.12065 0.3048)
			(end -0.67945 0.3048)
			(stroke
				(width 0.1)
				(type default)
			)
			(layer "F.Fab")
		)
		(fp_line
			(start -0.67945 0.3048)
			(end -0.67945 -0.305054)
			(stroke
				(width 0.1)
				(type default)
			)
			(layer "F.Fab")
		)
		(pad "1" smd circle
			(at -0.40005 0 90)
			(size 0 0)
			(layers "F.Cu" "F.Mask" "F.Paste")
			(net "PRSNT_NIC1_R_N")
		)
		(pad "2" smd circle
			(at 0.40005 0 90)
			(size 0 0)
			(layers "F.Cu" "F.Mask" "F.Paste")
			(net "GND")
		)
	)
	(footprint ""
		(layer "F.Cu")
		(at 223.139 -50.52695 90)
		(property "Reference" "R1779"
			(at 0 0 90)
			(layer "F.SilkS")
			(hide yes)
			(effects
				(font
					(size 1.27 1.27)
				)
			)
		)
		(property "Value" ""
			(at 0 0 90)
			(layer "F.Fab")
			(effects
				(font
					(size 1.27 1.27)
				)
			)
		)
		(duplicate_pad_numbers_are_jumpers no)
		(fp_line
			(start 0.7874 -0.4064)
			(end 0.7874 0.4064)
			(stroke
				(width 0.1524)
				(type default)
			)
			(layer "F.SilkS")
		)
		(fp_line
			(start -0.7874 -0.4064)
			(end 0.7874 -0.4064)
			(stroke
				(width 0.1524)
				(type default)
			)
			(layer "F.SilkS")
		)
		(fp_line
			(start 0.7874 0.4064)
			(end -0.7874 0.4064)
			(stroke
				(width 0.1524)
				(type default)
			)
			(layer "F.SilkS")
		)
		(fp_line
			(start -0.7874 0.4064)
			(end -0.7874 -0.4064)
			(stroke
				(width 0.1524)
				(type default)
			)
			(layer "F.SilkS")
		)
		(fp_line
			(start -0.12065 -0.305054)
			(end -0.12065 -0.2794)
			(stroke
				(width 0.1)
				(type default)
			)
			(layer "F.Fab")
		)
		(fp_line
			(start -0.67945 -0.305054)
			(end -0.12065 -0.305054)
			(stroke
				(width 0.1)
				(type default)
			)
			(layer "F.Fab")
		)
		(fp_line
			(start 0.67945 -0.3048)
			(end 0.67945 0.3048)
			(stroke
				(width 0.1)
				(type default)
			)
			(layer "F.Fab")
		)
		(fp_line
			(start 0.12065 -0.3048)
			(end 0.67945 -0.3048)
			(stroke
				(width 0.1)
				(type default)
			)
			(layer "F.Fab")
		)
		(fp_line
			(start 0.12065 -0.2794)
			(end 0.12065 -0.3048)
			(stroke
				(width 0.1)
				(type default)
			)
			(layer "F.Fab")
		)
		(fp_line
			(start -0.12065 -0.2794)
			(end 0.12065 -0.2794)
			(stroke
				(width 0.1)
				(type default)
			)
			(layer "F.Fab")
		)
		(fp_line
			(start 0.120396 0.2794)
			(end -0.12065 0.2794)
			(stroke
				(width 0.1)
				(type default)
			)
			(layer "F.Fab")
		)
		(fp_line
			(start -0.12065 0.2794)
			(end -0.12065 0.3048)
			(stroke
				(width 0.1)
				(type default)
			)
			(layer "F.Fab")
		)
		(fp_line
			(start 0.67945 0.3048)
			(end 0.120396 0.3048)
			(stroke
				(width 0.1)
				(type default)
			)
			(layer "F.Fab")
		)
		(fp_line
			(start 0.120396 0.3048)
			(end 0.120396 0.2794)
			(stroke
				(width 0.1)
				(type default)
			)
			(layer "F.Fab")
		)
		(fp_line
			(start -0.12065 0.3048)
			(end -0.67945 0.3048)
			(stroke
				(width 0.1)
				(type default)
			)
			(layer "F.Fab")
		)
		(fp_line
			(start -0.67945 0.3048)
			(end -0.67945 -0.305054)
			(stroke
				(width 0.1)
				(type default)
			)
			(layer "F.Fab")
		)
		(pad "1" smd circle
			(at -0.40005 0 90)
			(size 0 0)
			(layers "F.Cu" "F.Mask" "F.Paste")
			(net "SMB_BIC_I2C6_MUX_SSD_0_7_ADC_R_SCL")
		)
		(pad "2" smd circle
			(at 0.40005 0 90)
			(size 0 0)
			(layers "F.Cu" "F.Mask" "F.Paste")
			(net "SMB_BIC_I2C6_MUX_SSD_0_7_ADC_SCL")
		)
	)
	(footprint ""
		(layer "F.Cu")
		(at 268.19987 -393.099798)
		(property "Reference" "H46"
			(at -4.758182 -5.132324 0)
			(unlocked yes)
			(layer "F.SilkS")
			(effects
				(font
					(size 0.7874 0.5842)
					(thickness 0.1524)
				)
				(justify left)
			)
		)
		(property "Value" ""
			(at 0 0 0)
			(layer "F.Fab")
			(effects
				(font
					(size 1.27 1.27)
				)
			)
		)
		(duplicate_pad_numbers_are_jumpers no)
		(pad "1" thru_hole circle
			(at 0 0)
			(size 10.0076 10.0076)
			(drill 5.6134)
			(layers "*.Cu" "*.Mask")
			(remove_unused_layers no)
			(net "GND")
			(clearance -1.9431)
		)
	)
	(footprint ""
		(layer "F.Cu")
		(at 376.936 -188.849)
		(property "Reference" "R4609"
			(at 0 0 0)
			(layer "F.SilkS")
			(hide yes)
			(effects
				(font
					(size 1.27 1.27)
				)
			)
		)
		(property "Value" ""
			(at 0 0 0)
			(layer "F.Fab")
			(effects
				(font
					(size 1.27 1.27)
				)
			)
		)
		(duplicate_pad_numbers_are_jumpers no)
		(fp_line
			(start -0.7874 -0.4064)
			(end 0.7874 -0.4064)
			(stroke
				(width 0.1524)
				(type default)
			)
			(layer "F.SilkS")
		)
		(fp_line
			(start -0.7874 0.4064)
			(end -0.7874 -0.4064)
			(stroke
				(width 0.1524)
				(type default)
			)
			(layer "F.SilkS")
		)
		(fp_line
			(start 0.7874 -0.4064)
			(end 0.7874 0.4064)
			(stroke
				(width 0.1524)
				(type default)
			)
			(layer "F.SilkS")
		)
		(fp_line
			(start 0.7874 0.4064)
			(end -0.7874 0.4064)
			(stroke
				(width 0.1524)
				(type default)
			)
			(layer "F.SilkS")
		)
		(fp_line
			(start -0.67945 -0.305054)
			(end -0.12065 -0.305054)
			(stroke
				(width 0.1)
				(type default)
			)
			(layer "F.Fab")
		)
		(fp_line
			(start -0.67945 0.3048)
			(end -0.67945 -0.305054)
			(stroke
				(width 0.1)
				(type default)
			)
			(layer "F.Fab")
		)
		(fp_line
			(start -0.12065 -0.305054)
			(end -0.12065 -0.2794)
			(stroke
				(width 0.1)
				(type default)
			)
			(layer "F.Fab")
		)
		(fp_line
			(start -0.12065 -0.2794)
			(end 0.12065 -0.2794)
			(stroke
				(width 0.1)
				(type default)
			)
			(layer "F.Fab")
		)
		(fp_line
			(start -0.12065 0.2794)
			(end -0.12065 0.3048)
			(stroke
				(width 0.1)
				(type default)
			)
			(layer "F.Fab")
		)
		(fp_line
			(start -0.12065 0.3048)
			(end -0.67945 0.3048)
			(stroke
				(width 0.1)
				(type default)
			)
			(layer "F.Fab")
		)
		(fp_line
			(start 0.120396 0.2794)
			(end -0.12065 0.2794)
			(stroke
				(width 0.1)
				(type default)
			)
			(layer "F.Fab")
		)
		(fp_line
			(start 0.120396 0.3048)
			(end 0.120396 0.2794)
			(stroke
				(width 0.1)
				(type default)
			)
			(layer "F.Fab")
		)
		(fp_line
			(start 0.12065 -0.3048)
			(end 0.67945 -0.3048)
			(stroke
				(width 0.1)
				(type default)
			)
			(layer "F.Fab")
		)
		(fp_line
			(start 0.12065 -0.2794)
			(end 0.12065 -0.3048)
			(stroke
				(width 0.1)
				(type default)
			)
			(layer "F.Fab")
		)
		(fp_line
			(start 0.67945 -0.3048)
			(end 0.67945 0.3048)
			(stroke
				(width 0.1)
				(type default)
			)
			(layer "F.Fab")
		)
		(fp_line
			(start 0.67945 0.3048)
			(end 0.120396 0.3048)
			(stroke
				(width 0.1)
				(type default)
			)
			(layer "F.Fab")
		)
		(pad "1" smd circle
			(at -0.40005 0)
			(size 0 0)
			(layers "F.Cu" "F.Mask" "F.Paste")
			(net "P3V3_AUX")
		)
		(pad "2" smd circle
			(at 0.40005 0)
			(size 0 0)
			(layers "F.Cu" "F.Mask" "F.Paste")
			(net "RST_PEX_NIC1_PERST_R_N")
		)
	)
	(footprint ""
		(layer "F.Cu")
		(at 284.330902 -356.244906 90)
		(property "Reference" "C598"
			(at 0 0 90)
			(layer "F.SilkS")
			(hide yes)
			(effects
				(font
					(size 1.27 1.27)
				)
			)
		)
		(property "Value" ""
			(at 0 0 90)
			(layer "F.Fab")
			(effects
				(font
					(size 1.27 1.27)
				)
			)
		)
		(duplicate_pad_numbers_are_jumpers no)
		(fp_line
			(start 0.299974 -0.150114)
			(end 0.299974 0.150114)
			(stroke
				(width 0.1)
				(type default)
			)
			(layer "F.Fab")
		)
		(fp_line
			(start -0.299974 -0.150114)
			(end 0.299974 -0.150114)
			(stroke
				(width 0.1)
				(type default)
			)
			(layer "F.Fab")
		)
		(fp_line
			(start 0.299974 0.150114)
			(end -0.299974 0.150114)
			(stroke
				(width 0.1)
				(type default)
			)
			(layer "F.Fab")
		)
		(fp_line
			(start -0.299974 0.150114)
			(end -0.299974 -0.150114)
			(stroke
				(width 0.1)
				(type default)
			)
			(layer "F.Fab")
		)
		(pad "1" smd rect
			(at -0.2667 0 90)
			(size 0.3048 0.381)
			(layers "F.Cu" "F.Mask" "F.Paste")
			(net "P5E_PEX2_STN7_TX_DN<120>")
		)
		(pad "2" smd rect
			(at 0.2667 0 90)
			(size 0.3048 0.381)
			(layers "F.Cu" "F.Mask" "F.Paste")
			(net "P5E_PEX2_STN7_TX_C_DN<120>")
		)
	)
	(footprint ""
		(layer "F.Cu")
		(at 191.767968 -18.430748)
		(property "Reference" "R1679"
			(at 0 0 0)
			(layer "F.SilkS")
			(hide yes)
			(effects
				(font
					(size 1.27 1.27)
				)
			)
		)
		(property "Value" ""
			(at 0 0 0)
			(layer "F.Fab")
			(effects
				(font
					(size 1.27 1.27)
				)
			)
		)
		(duplicate_pad_numbers_are_jumpers no)
		(fp_line
			(start -0.7874 -0.4064)
			(end 0.7874 -0.4064)
			(stroke
				(width 0.1524)
				(type default)
			)
			(layer "F.SilkS")
		)
		(fp_line
			(start -0.7874 0.4064)
			(end -0.7874 -0.4064)
			(stroke
				(width 0.1524)
				(type default)
			)
			(layer "F.SilkS")
		)
		(fp_line
			(start 0.7874 -0.4064)
			(end 0.7874 0.4064)
			(stroke
				(width 0.1524)
				(type default)
			)
			(layer "F.SilkS")
		)
		(fp_line
			(start 0.7874 0.4064)
			(end -0.7874 0.4064)
			(stroke
				(width 0.1524)
				(type default)
			)
			(layer "F.SilkS")
		)
		(fp_line
			(start -0.67945 -0.305054)
			(end -0.12065 -0.305054)
			(stroke
				(width 0.1)
				(type default)
			)
			(layer "F.Fab")
		)
		(fp_line
			(start -0.67945 0.3048)
			(end -0.67945 -0.305054)
			(stroke
				(width 0.1)
				(type default)
			)
			(layer "F.Fab")
		)
		(fp_line
			(start -0.12065 -0.305054)
			(end -0.12065 -0.2794)
			(stroke
				(width 0.1)
				(type default)
			)
			(layer "F.Fab")
		)
		(fp_line
			(start -0.12065 -0.2794)
			(end 0.12065 -0.2794)
			(stroke
				(width 0.1)
				(type default)
			)
			(layer "F.Fab")
		)
		(fp_line
			(start -0.12065 0.2794)
			(end -0.12065 0.3048)
			(stroke
				(width 0.1)
				(type default)
			)
			(layer "F.Fab")
		)
		(fp_line
			(start -0.12065 0.3048)
			(end -0.67945 0.3048)
			(stroke
				(width 0.1)
				(type default)
			)
			(layer "F.Fab")
		)
		(fp_line
			(start 0.120396 0.2794)
			(end -0.12065 0.2794)
			(stroke
				(width 0.1)
				(type default)
			)
			(layer "F.Fab")
		)
		(fp_line
			(start 0.120396 0.3048)
			(end 0.120396 0.2794)
			(stroke
				(width 0.1)
				(type default)
			)
			(layer "F.Fab")
		)
		(fp_line
			(start 0.12065 -0.3048)
			(end 0.67945 -0.3048)
			(stroke
				(width 0.1)
				(type default)
			)
			(layer "F.Fab")
		)
		(fp_line
			(start 0.12065 -0.2794)
			(end 0.12065 -0.3048)
			(stroke
				(width 0.1)
				(type default)
			)
			(layer "F.Fab")
		)
		(fp_line
			(start 0.67945 -0.3048)
			(end 0.67945 0.3048)
			(stroke
				(width 0.1)
				(type default)
			)
			(layer "F.Fab")
		)
		(fp_line
			(start 0.67945 0.3048)
			(end 0.120396 0.3048)
			(stroke
				(width 0.1)
				(type default)
			)
			(layer "F.Fab")
		)
		(pad "1" smd circle
			(at -0.40005 0)
			(size 0 0)
			(layers "F.Cu" "F.Mask" "F.Paste")
			(net "SMB_ISO_SSD6_R_SCL")
		)
		(pad "2" smd circle
			(at 0.40005 0)
			(size 0 0)
			(layers "F.Cu" "F.Mask" "F.Paste")
			(net "SMB_ISO_SSD6_SCL")
		)
	)
	(footprint ""
		(layer "F.Cu")
		(at 318.695324 -343.952322 90)
		(property "Reference" "C555"
			(at 0 0 90)
			(layer "F.SilkS")
			(hide yes)
			(effects
				(font
					(size 1.27 1.27)
				)
			)
		)
		(property "Value" ""
			(at 0 0 90)
			(layer "F.Fab")
			(effects
				(font
					(size 1.27 1.27)
				)
			)
		)
		(duplicate_pad_numbers_are_jumpers no)
		(fp_line
			(start 0.299974 -0.150114)
			(end 0.299974 0.150114)
			(stroke
				(width 0.1)
				(type default)
			)
			(layer "F.Fab")
		)
		(fp_line
			(start -0.299974 -0.150114)
			(end 0.299974 -0.150114)
			(stroke
				(width 0.1)
				(type default)
			)
			(layer "F.Fab")
		)
		(fp_line
			(start 0.299974 0.150114)
			(end -0.299974 0.150114)
			(stroke
				(width 0.1)
				(type default)
			)
			(layer "F.Fab")
		)
		(fp_line
			(start -0.299974 0.150114)
			(end -0.299974 -0.150114)
			(stroke
				(width 0.1)
				(type default)
			)
			(layer "F.Fab")
		)
		(pad "1" smd rect
			(at -0.2667 0 90)
			(size 0.3048 0.381)
			(layers "F.Cu" "F.Mask" "F.Paste")
			(net "P5E_PEX2_STN6_TX_DP<109>")
		)
		(pad "2" smd rect
			(at 0.2667 0 90)
			(size 0.3048 0.381)
			(layers "F.Cu" "F.Mask" "F.Paste")
			(net "P5E_PEX2_STN6_TX_C_DP<109>")
		)
	)
	(footprint ""
		(layer "F.Cu")
		(at 344.043 -234.061 -90)
		(property "Reference" "R3541"
			(at 0 0 270)
			(layer "F.SilkS")
			(hide yes)
			(effects
				(font
					(size 1.27 1.27)
				)
			)
		)
		(property "Value" ""
			(at 0 0 270)
			(layer "F.Fab")
			(effects
				(font
					(size 1.27 1.27)
				)
			)
		)
		(duplicate_pad_numbers_are_jumpers no)
		(fp_line
			(start -0.7874 0.4064)
			(end -0.7874 -0.4064)
			(stroke
				(width 0.1524)
				(type default)
			)
			(layer "F.SilkS")
		)
		(fp_line
			(start 0.7874 0.4064)
			(end -0.7874 0.4064)
			(stroke
				(width 0.1524)
				(type default)
			)
			(layer "F.SilkS")
		)
		(fp_line
			(start -0.7874 -0.4064)
			(end 0.7874 -0.4064)
			(stroke
				(width 0.1524)
				(type default)
			)
			(layer "F.SilkS")
		)
		(fp_line
			(start 0.7874 -0.4064)
			(end 0.7874 0.4064)
			(stroke
				(width 0.1524)
				(type default)
			)
			(layer "F.SilkS")
		)
		(fp_line
			(start -0.67945 0.3048)
			(end -0.67945 -0.305054)
			(stroke
				(width 0.1)
				(type default)
			)
			(layer "F.Fab")
		)
		(fp_line
			(start -0.12065 0.3048)
			(end -0.67945 0.3048)
			(stroke
				(width 0.1)
				(type default)
			)
			(layer "F.Fab")
		)
		(fp_line
			(start 0.120396 0.3048)
			(end 0.120396 0.2794)
			(stroke
				(width 0.1)
				(type default)
			)
			(layer "F.Fab")
		)
		(fp_line
			(start 0.67945 0.3048)
			(end 0.120396 0.3048)
			(stroke
				(width 0.1)
				(type default)
			)
			(layer "F.Fab")
		)
		(fp_line
			(start -0.12065 0.2794)
			(end -0.12065 0.3048)
			(stroke
				(width 0.1)
				(type default)
			)
			(layer "F.Fab")
		)
		(fp_line
			(start 0.120396 0.2794)
			(end -0.12065 0.2794)
			(stroke
				(width 0.1)
				(type default)
			)
			(layer "F.Fab")
		)
		(fp_line
			(start -0.12065 -0.2794)
			(end 0.12065 -0.2794)
			(stroke
				(width 0.1)
				(type default)
			)
			(layer "F.Fab")
		)
		(fp_line
			(start 0.12065 -0.2794)
			(end 0.12065 -0.3048)
			(stroke
				(width 0.1)
				(type default)
			)
			(layer "F.Fab")
		)
		(fp_line
			(start 0.12065 -0.3048)
			(end 0.67945 -0.3048)
			(stroke
				(width 0.1)
				(type default)
			)
			(layer "F.Fab")
		)
		(fp_line
			(start 0.67945 -0.3048)
			(end 0.67945 0.3048)
			(stroke
				(width 0.1)
				(type default)
			)
			(layer "F.Fab")
		)
		(fp_line
			(start -0.67945 -0.305054)
			(end -0.12065 -0.305054)
			(stroke
				(width 0.1)
				(type default)
			)
			(layer "F.Fab")
		)
		(fp_line
			(start -0.12065 -0.305054)
			(end -0.12065 -0.2794)
			(stroke
				(width 0.1)
				(type default)
			)
			(layer "F.Fab")
		)
		(pad "1" smd circle
			(at -0.40005 0 270)
			(size 0 0)
			(layers "F.Cu" "F.Mask" "F.Paste")
			(net "SSD3_CLK_EN_R_N")
		)
		(pad "2" smd circle
			(at 0.40005 0 270)
			(size 0 0)
			(layers "F.Cu" "F.Mask" "F.Paste")
			(net "SSD3_CLK_EN_N")
		)
	)
)
